# T6G (Grand Teton) — schematic netlist excerpt (pin names and nets, part order shuffled) for the footprints in the layout excerpt that follows; sources: Cadence DE-HDL packaged netlist, KiCad conversion of 04192023_DAF0TMB3IC0_F0TG_MB_C_brd_V02_OCP.brd

J105  CONN112_10137002101LF  CONN112_10137002-101LF IO  pkg HSD_F112D8_P2W1-2_RDH  page 115
  A1  = GPU_3V3IO_RSVD4
  A2  = GND
  A3  = GPU_WP_HW_CTRL_ISO_N
  A4  = GND
  A5  = GPU_3V3IO_RSVD3
  A6  = GND
  A7  = GPU_3V3IO_RSVD1
  A8  = GND
  B1  = GND
  B2  = P5E_CPU0_P2_RX_BUF_DN<9>
  B3  = GND
  B4  = P5E_CPU0_P2_RX_BUF_DN<11>
  B5  = GND
  B6  = P5E_CPU0_P2_RX_BUF_DN<13>
  B7  = GND
  B8  = P5E_CPU0_P2_RX_BUF_DN<15>
  C1  = P5E_CPU0_P2_RX_BUF_DN<8>
  C2  = P5E_CPU0_P2_RX_BUF_DP<9>
  C3  = P5E_CPU0_P2_RX_BUF_DN<10>
  C4  = P5E_CPU0_P2_RX_BUF_DP<11>
  C5  = P5E_CPU0_P2_RX_BUF_DN<12>
  C6  = P5E_CPU0_P2_RX_BUF_DP<13>
  C7  = P5E_CPU0_P2_RX_BUF_DN<14>
  C8  = P5E_CPU0_P2_RX_BUF_DP<15>
  D1  = P5E_CPU0_P2_RX_BUF_DP<8>
  D2  = GND
  D3  = P5E_CPU0_P2_RX_BUF_DP<10>
  D4  = GND
  D5  = P5E_CPU0_P2_RX_BUF_DP<12>
  D6  = GND
  D7  = P5E_CPU0_P2_RX_BUF_DP<14>
  D8  = GND
  E1  = GND
  E2  = P5E_CPU0_P3_RX_BUF_DN<9>
  E3  = GND
  E4  = P5E_CPU0_P3_RX_BUF_DN<11>
  E5  = GND
  E6  = P5E_CPU0_P3_RX_BUF_DN<13>
  E7  = GND
  E8  = P5E_CPU0_P3_RX_BUF_DN<15>
  F1  = P5E_CPU0_P3_RX_BUF_DN<8>
  F2  = P5E_CPU0_P3_RX_BUF_DP<9>
  F3  = P5E_CPU0_P3_RX_BUF_DN<10>
  F4  = P5E_CPU0_P3_RX_BUF_DP<11>
  F5  = P5E_CPU0_P3_RX_BUF_DN<12>
  F6  = P5E_CPU0_P3_RX_BUF_DP<13>
  F7  = P5E_CPU0_P3_RX_BUF_DN<14>
  F8  = P5E_CPU0_P3_RX_BUF_DP<15>
  G1  = P5E_CPU0_P3_RX_BUF_DP<8>
  G2  = GND
  G3  = P5E_CPU0_P3_RX_BUF_DP<10>
  G4  = GND
  G5  = P5E_CPU0_P3_RX_BUF_DP<12>
  G6  = GND
  G7  = P5E_CPU0_P3_RX_BUF_DP<14>
  G8  = GND
  H1  = GND
  H2  = P5E_CPU0_P2_TX_BUF_C_DN<9>
  H3  = GND
  H4  = P5E_CPU0_P2_TX_BUF_C_DN<11>
  H5  = GND
  H6  = P5E_CPU0_P2_TX_BUF_C_DN<13>
  H7  = GND
  H8  = P5E_CPU0_P2_TX_BUF_C_DN<15>
  I1  = P5E_CPU0_P2_TX_BUF_C_DN<8>
  I2  = P5E_CPU0_P2_TX_BUF_C_DP<9>
  I3  = P5E_CPU0_P2_TX_BUF_C_DN<10>
  I4  = P5E_CPU0_P2_TX_BUF_C_DP<11>
  I5  = P5E_CPU0_P2_TX_BUF_C_DN<12>
  I6  = P5E_CPU0_P2_TX_BUF_C_DP<13>
  I7  = P5E_CPU0_P2_TX_BUF_C_DN<14>
  I8  = P5E_CPU0_P2_TX_BUF_C_DP<15>
  J1  = P5E_CPU0_P2_TX_BUF_C_DP<8>
  J2  = GND
  J3  = P5E_CPU0_P2_TX_BUF_C_DP<10>
  J4  = GND
  J5  = P5E_CPU0_P2_TX_BUF_C_DP<12>
  J6  = GND
  J7  = P5E_CPU0_P2_TX_BUF_C_DP<14>
  J8  = GND
  K1  = GND
  K2  = P5E_CPU0_P3_TX_BUF_C_DN<9>
  K3  = GND
  K4  = P5E_CPU0_P3_TX_BUF_C_DN<11>
  K5  = GND
  K6  = P5E_CPU0_P3_TX_BUF_C_DN<13>
  K7  = GND
  K8  = P5E_CPU0_P3_TX_BUF_C_DN<15>
  L1  = P5E_CPU0_P3_TX_BUF_C_DN<8>
  L2  = P5E_CPU0_P3_TX_BUF_C_DP<9>
  L3  = P5E_CPU0_P3_TX_BUF_C_DN<10>
  L4  = P5E_CPU0_P3_TX_BUF_C_DP<11>
  L5  = P5E_CPU0_P3_TX_BUF_C_DN<12>
  L6  = P5E_CPU0_P3_TX_BUF_C_DP<13>
  L7  = P5E_CPU0_P3_TX_BUF_C_DN<14>
  L8  = P5E_CPU0_P3_TX_BUF_C_DP<15>
  M1  = P5E_CPU0_P3_TX_BUF_C_DP<8>
  M2  = GND
  M3  = P5E_CPU0_P3_TX_BUF_C_DP<10>
  M4  = GND
  M5  = P5E_CPU0_P3_TX_BUF_C_DP<12>
  M6  = GND
  M7  = P5E_CPU0_P3_TX_BUF_C_DP<14>
  M8  = GND
  N1  = GND
  N2  = FM_SWB_PWR_EN_R_BUF
  N3  = GND
  N4  = FM_SWB_BIC_READY_N
  N5  = GND
  N6  = RST_SWB_BIC_BUF_N
  N7  = GND
  N8  = RST_BMC_FROM_SWB_N

(kicad_pcb
	(version 20260206)
	(generator "pcbnew")
	(generator_version "10.0")
	(general
		(thickness 1.6)
		(legacy_teardrops no)
	)
	(paper "A4")
	(title_block
		(title "04192023_DAF0TMB3IC0_F0TG_MB_C_brd_V02_OCP.brd")
		(comment 1 "Grand Teton / footprint 3508 of 8354 (J105), pads 1-31 of 48")
	)
	(layers
		(0 "F.Cu" signal "TOP")
		(4 "In1.Cu" signal "GND")
		(6 "In2.Cu" signal "IN1")
		(8 "In3.Cu" signal "GND1")
		(10 "In4.Cu" signal "IN2")
		(12 "In5.Cu" signal "GND2")
		(14 "In6.Cu" signal "IN3")
		(16 "In7.Cu" signal "GND3")
		(18 "In8.Cu" signal "VCC")
		(20 "In9.Cu" signal "VCC1")
		(22 "In10.Cu" signal "GND4")
		(24 "In11.Cu" signal "IN4")
		(26 "In12.Cu" signal "GND5")
		(28 "In13.Cu" signal "IN5")
		(30 "In14.Cu" signal "GND6")
		(32 "In15.Cu" signal "IN6")
		(34 "In16.Cu" signal "GND7")
		(2 "B.Cu" signal "BOTTOM")
		(9 "F.Adhes" user "F.Adhesive")
		(11 "B.Adhes" user "B.Adhesive")
		(13 "F.Paste" user "Package Geometry/Pastemask Top")
		(15 "B.Paste" user "Package Geometry/Pastemask Bottom")
		(5 "F.SilkS" user "Ref Des/Silkscreen Top")
		(7 "B.SilkS" user "Ref Des/Silkscreen Bottom")
		(1 "F.Mask" user "Board Geometry/Soldermask Top")
		(3 "B.Mask" user "Board Geometry/Soldermask Bottom")
		(17 "Dwgs.User" user "User.Drawings")
		(19 "Cmts.User" user "User.Comments")
		(21 "Eco1.User" user "User.Eco1")
		(23 "Eco2.User" user "User.Eco2")
		(25 "Edge.Cuts" user "Board Geometry/Outline")
		(27 "Margin" user)
		(31 "F.CrtYd" user "Package Geometry/Place Bound Top")
		(29 "B.CrtYd" user "Package Geometry/Place Bound Bottom")
		(35 "F.Fab" user "Ref Des/Assembly Top")
		(33 "B.Fab" user "Ref Des/Assembly Bottom")
	)
	(footprint ""
		(layer "F.Cu")
		(at 398.750028 -440.489848)
		(property "Reference" "J105"
			(at 19.875754 19.509486 0)
			(unlocked yes)
			(layer "F.SilkS")
			(effects
				(font
					(size 0.7874 0.5842)
					(thickness 0.1524)
				)
				(justify left)
			)
		)
		(property "Value" ""
			(at 0 0 0)
			(layer "F.Fab")
			(effects
				(font
					(size 1.27 1.27)
				)
			)
		)
		(duplicate_pad_numbers_are_jumpers no)
		(pad "A1" thru_hole rect
			(at 0 0 180)
			(size 0.766318 0.766318)
			(drill 0.359918)
			(layers "*.Cu" "*.Mask")
			(remove_unused_layers no)
			(net "GPU_3V3IO_RSVD4")
			(clearance 0.0508)
			(thermal_gap 0.0508)
			(padstack
				(mode front_inner_back)
				(layer "Inner"
					(shape circle)
					(size 0.766318 0.766318)
					(clearance 0.0508)
				)
				(layer "B.Cu"
					(shape rect)
					(size 0.766318 0.766318)
					(clearance 0.0508)
				)
			)
		)
		(pad "A2" thru_hole circle
			(at 1.999996 0.199898 180)
			(size 0.906272 0.906272)
			(drill 0.499872)
			(layers "*.Cu" "*.Mask")
			(remove_unused_layers no)
			(net "GND")
			(clearance 0.0508)
			(thermal_gap 0.0508)
		)
		(pad "A3" thru_hole circle
			(at 3.999992 0 180)
			(size 0.766318 0.766318)
			(drill 0.359918)
			(layers "*.Cu" "*.Mask")
			(remove_unused_layers no)
			(net "GPU_WP_HW_CTRL_ISO_N")
			(clearance 0.0508)
			(thermal_gap 0.0508)
		)
		(pad "A4" thru_hole circle
			(at 5.999988 0.199898 180)
			(size 0.906272 0.906272)
			(drill 0.499872)
			(layers "*.Cu" "*.Mask")
			(remove_unused_layers no)
			(net "GND")
			(clearance 0.0508)
			(thermal_gap 0.0508)
		)
		(pad "A5" thru_hole circle
			(at 7.999984 0 180)
			(size 0.766318 0.766318)
			(drill 0.359918)
			(layers "*.Cu" "*.Mask")
			(remove_unused_layers no)
			(net "GPU_3V3IO_RSVD3")
			(clearance 0.0508)
			(thermal_gap 0.0508)
		)
		(pad "A6" thru_hole circle
			(at 9.99998 0.199898 180)
			(size 0.906272 0.906272)
			(drill 0.499872)
			(layers "*.Cu" "*.Mask")
			(remove_unused_layers no)
			(net "GND")
			(clearance 0.0508)
			(thermal_gap 0.0508)
		)
		(pad "A7" thru_hole circle
			(at 11.999976 0 180)
			(size 0.766318 0.766318)
			(drill 0.359918)
			(layers "*.Cu" "*.Mask")
			(remove_unused_layers no)
			(net "GPU_3V3IO_RSVD1")
			(clearance 0.0508)
			(thermal_gap 0.0508)
		)
		(pad "A8" thru_hole circle
			(at 13.999972 0.199898 180)
			(size 0.906272 0.906272)
			(drill 0.499872)
			(layers "*.Cu" "*.Mask")
			(remove_unused_layers no)
			(net "GND")
			(clearance 0.0508)
			(thermal_gap 0.0508)
		)
		(pad "B1" thru_hole circle
			(at 0 1.199896 180)
			(size 0.906272 0.906272)
			(drill 0.499872)
			(layers "*.Cu" "*.Mask")
			(remove_unused_layers no)
			(net "GND")
			(clearance 0.0508)
			(thermal_gap 0.0508)
		)
		(pad "B3" thru_hole circle
			(at 3.999992 1.199896 180)
			(size 0.906272 0.906272)
			(drill 0.499872)
			(layers "*.Cu" "*.Mask")
			(remove_unused_layers no)
			(net "GND")
			(clearance 0.0508)
			(thermal_gap 0.0508)
		)
		(pad "B5" thru_hole circle
			(at 7.999984 1.199896 180)
			(size 0.906272 0.906272)
			(drill 0.499872)
			(layers "*.Cu" "*.Mask")
			(remove_unused_layers no)
			(net "GND")
			(clearance 0.0508)
			(thermal_gap 0.0508)
		)
		(pad "B7" thru_hole circle
			(at 11.999976 1.199896 180)
			(size 0.906272 0.906272)
			(drill 0.499872)
			(layers "*.Cu" "*.Mask")
			(remove_unused_layers no)
			(net "GND")
			(clearance 0.0508)
			(thermal_gap 0.0508)
		)
		(pad "D2" thru_hole circle
			(at 1.999996 3.800094 180)
			(size 0.906272 0.906272)
			(drill 0.499872)
			(layers "*.Cu" "*.Mask")
			(remove_unused_layers no)
			(net "GND")
			(clearance 0.0508)
			(thermal_gap 0.0508)
		)
		(pad "D4" thru_hole circle
			(at 5.999988 3.800094 180)
			(size 0.906272 0.906272)
			(drill 0.499872)
			(layers "*.Cu" "*.Mask")
			(remove_unused_layers no)
			(net "GND")
			(clearance 0.0508)
			(thermal_gap 0.0508)
		)
		(pad "D6" thru_hole circle
			(at 9.99998 3.800094 180)
			(size 0.906272 0.906272)
			(drill 0.499872)
			(layers "*.Cu" "*.Mask")
			(remove_unused_layers no)
			(net "GND")
			(clearance 0.0508)
			(thermal_gap 0.0508)
		)
		(pad "D8" thru_hole circle
			(at 13.999972 3.800094 180)
			(size 0.906272 0.906272)
			(drill 0.499872)
			(layers "*.Cu" "*.Mask")
			(remove_unused_layers no)
			(net "GND")
			(clearance 0.0508)
			(thermal_gap 0.0508)
		)
		(pad "E1" thru_hole circle
			(at 0 4.800092 180)
			(size 0.906272 0.906272)
			(drill 0.499872)
			(layers "*.Cu" "*.Mask")
			(remove_unused_layers no)
			(net "GND")
			(clearance 0.0508)
			(thermal_gap 0.0508)
		)
		(pad "E3" thru_hole circle
			(at 3.999992 4.800092 180)
			(size 0.906272 0.906272)
			(drill 0.499872)
			(layers "*.Cu" "*.Mask")
			(remove_unused_layers no)
			(net "GND")
			(clearance 0.0508)
			(thermal_gap 0.0508)
		)
		(pad "E5" thru_hole circle
			(at 7.999984 4.800092 180)
			(size 0.906272 0.906272)
			(drill 0.499872)
			(layers "*.Cu" "*.Mask")
			(remove_unused_layers no)
			(net "GND")
			(clearance 0.0508)
			(thermal_gap 0.0508)
		)
		(pad "E7" thru_hole circle
			(at 11.999976 4.800092 180)
			(size 0.906272 0.906272)
			(drill 0.499872)
			(layers "*.Cu" "*.Mask")
			(remove_unused_layers no)
			(net "GND")
			(clearance 0.0508)
			(thermal_gap 0.0508)
		)
		(pad "G2" thru_hole circle
			(at 1.999996 7.400036 180)
			(size 0.906272 0.906272)
			(drill 0.499872)
			(layers "*.Cu" "*.Mask")
			(remove_unused_layers no)
			(net "GND")
			(clearance 0.0508)
			(thermal_gap 0.0508)
		)
		(pad "G4" thru_hole circle
			(at 5.999988 7.400036 180)
			(size 0.906272 0.906272)
			(drill 0.499872)
			(layers "*.Cu" "*.Mask")
			(remove_unused_layers no)
			(net "GND")
			(clearance 0.0508)
			(thermal_gap 0.0508)
		)
		(pad "G6" thru_hole circle
			(at 9.99998 7.400036 180)
			(size 0.906272 0.906272)
			(drill 0.499872)
			(layers "*.Cu" "*.Mask")
			(remove_unused_layers no)
			(net "GND")
			(clearance 0.0508)
			(thermal_gap 0.0508)
		)
		(pad "G8" thru_hole circle
			(at 13.999972 7.400036 180)
			(size 0.906272 0.906272)
			(drill 0.499872)
			(layers "*.Cu" "*.Mask")
			(remove_unused_layers no)
			(net "GND")
			(clearance 0.0508)
			(thermal_gap 0.0508)
		)
		(pad "H1" thru_hole circle
			(at 0 8.400034 180)
			(size 0.906272 0.906272)
			(drill 0.499872)
			(layers "*.Cu" "*.Mask")
			(remove_unused_layers no)
			(net "GND")
			(clearance 0.0508)
			(thermal_gap 0.0508)
		)
		(pad "H3" thru_hole circle
			(at 3.999992 8.400034 180)
			(size 0.906272 0.906272)
			(drill 0.499872)
			(layers "*.Cu" "*.Mask")
			(remove_unused_layers no)
			(net "GND")
			(clearance 0.0508)
			(thermal_gap 0.0508)
		)
		(pad "H5" thru_hole circle
			(at 7.999984 8.400034 180)
			(size 0.906272 0.906272)
			(drill 0.499872)
			(layers "*.Cu" "*.Mask")
			(remove_unused_layers no)
			(net "GND")
			(clearance 0.0508)
			(thermal_gap 0.0508)
		)
		(pad "H7" thru_hole circle
			(at 11.999976 8.400034 180)
			(size 0.906272 0.906272)
			(drill 0.499872)
			(layers "*.Cu" "*.Mask")
			(remove_unused_layers no)
			(net "GND")
			(clearance 0.0508)
			(thermal_gap 0.0508)
		)
		(pad "J2" thru_hole circle
			(at 1.999996 10.999978 180)
			(size 0.906272 0.906272)
			(drill 0.499872)
			(layers "*.Cu" "*.Mask")
			(remove_unused_layers no)
			(net "GND")
			(clearance 0.0508)
			(thermal_gap 0.0508)
		)
		(pad "J4" thru_hole circle
			(at 5.999988 10.999978 180)
			(size 0.906272 0.906272)
			(drill 0.499872)
			(layers "*.Cu" "*.Mask")
			(remove_unused_layers no)
			(net "GND")
			(clearance 0.0508)
			(thermal_gap 0.0508)
		)
		(pad "J6" thru_hole circle
			(at 9.99998 10.999978 180)
			(size 0.906272 0.906272)
			(drill 0.499872)
			(layers "*.Cu" "*.Mask")
			(remove_unused_layers no)
			(net "GND")
			(clearance 0.0508)
			(thermal_gap 0.0508)
		)
	)
)
